(kicad_pcb
	(version 20260206)
	(generator "pcbnew")
	(generator_version "10.0")
	(general
		(thickness 1.6)
		(legacy_teardrops no)
	)
	(paper "A4")
	(title_block
		(title "peb — Lightning_PEB_BRD.brd")
		(comment 1 "Lightning (Wiwynn / Facebook NVMe JBOF) / footprints 1701-1708 of 2563")
	)
	(layers
		(0 "F.Cu" signal "TOP")
		(4 "In1.Cu" signal "L2GND")
		(6 "In2.Cu" signal "L3")
		(8 "In3.Cu" signal "L4VCC")
		(10 "In4.Cu" signal "L5VCC")
		(12 "In5.Cu" signal "L6")
		(14 "In6.Cu" signal "L7GND")
		(2 "B.Cu" signal "BOTTOM")
		(9 "F.Adhes" user "F.Adhesive")
		(11 "B.Adhes" user "B.Adhesive")
		(13 "F.Paste" user "Package Geometry/Pastemask Top")
		(15 "B.Paste" user "Package Geometry/Pastemask Bottom")
		(5 "F.SilkS" user "Ref Des/Silkscreen Top")
		(7 "B.SilkS" user "Ref Des/Silkscreen Bottom")
		(1 "F.Mask" user "Board Geometry/Soldermask Top")
		(3 "B.Mask" user "Board Geometry/Soldermask Bottom")
		(17 "Dwgs.User" user "User.Drawings")
		(19 "Cmts.User" user "User.Comments")
		(21 "Eco1.User" user "User.Eco1")
		(23 "Eco2.User" user "User.Eco2")
		(25 "Edge.Cuts" user "Board Geometry/Outline")
		(27 "Margin" user)
		(31 "F.CrtYd" user "Package Geometry/Place Bound Top")
		(29 "B.CrtYd" user "Package Geometry/Place Bound Bottom")
		(35 "F.Fab" user "Ref Des/Assembly Top")
		(33 "B.Fab" user "Ref Des/Assembly Bottom")
	)
	(footprint ""
		(layer "B.Cu")
		(at 33.456372 -126.665228)
		(property "Reference" "TP270"
			(at 0 0 0)
			(layer "B.SilkS")
			(hide yes)
			(effects
				(font
					(size 1.27 1.27)
				)
				(justify mirror)
			)
		)
		(property "Value" "TPAD28-2-GP"
			(at 0.0127 -1.6637 0)
			(unlocked yes)
			(layer "B.Fab")
			(hide yes)
			(effects
				(font
					(size 1.016 1.016)
					(thickness 0.1524)
				)
				(justify mirror)
			)
		)
		(property "Device Type" "TPAD28"
			(at 0.0127 -3.1877 0)
			(unlocked yes)
			(layer "B.Fab")
			(hide yes)
			(effects
				(font
					(size 1.016 1.016)
					(thickness 0.1524)
				)
				(justify mirror)
			)
		)
		(duplicate_pad_numbers_are_jumpers no)
		(fp_poly
			(pts
				(arc
					(start 0.3556 0)
					(mid -0.3556 0)
					(end 0.3556 0)
				)
			)
			(stroke
				(width 0)
				(type default)
			)
			(fill no)
			(layer "B.CrtYd")
		)
		(fp_poly
			(pts
				(arc
					(start 0.6096 0)
					(mid -0.6096 0)
					(end 0.6096 0)
				)
			)
			(stroke
				(width 0)
				(type default)
			)
			(fill no)
			(layer "B.Fab")
		)
		(pad "1" smd circle
			(at 0 0 180)
			(size 0.7112 0.7112)
			(layers "B.Cu" "B.Mask" "B.Paste")
			(net "TP_GPIOI1")
		)
	)
	(footprint ""
		(layer "B.Cu")
		(at 227.965 -23.241 180)
		(property "Reference" "R827"
			(at 0 0 0)
			(layer "B.SilkS")
			(hide yes)
			(effects
				(font
					(size 1.27 1.27)
				)
				(justify mirror)
			)
		)
		(property "Value" "0R2J-2-GP"
			(at -0.064008 -3.993896 180)
			(unlocked yes)
			(layer "B.Fab")
			(hide yes)
			(effects
				(font
					(size 1.016 1.016)
					(thickness 0.1524)
				)
				(justify mirror)
			)
		)
		(property "Device Type" "R402H16"
			(at -0.064008 -5.517896 180)
			(unlocked yes)
			(layer "B.Fab")
			(hide yes)
			(effects
				(font
					(size 1.016 1.016)
					(thickness 0.1524)
				)
				(justify mirror)
			)
		)
		(duplicate_pad_numbers_are_jumpers no)
		(fp_line
			(start 0.508 -0.9398)
			(end 0.508 0.9398)
			(stroke
				(width 0.1524)
				(type default)
			)
			(layer "B.SilkS")
		)
		(fp_line
			(start -0.508 -0.9398)
			(end 0.508 -0.9398)
			(stroke
				(width 0.1524)
				(type default)
			)
			(layer "B.SilkS")
		)
		(fp_rect
			(start 0.508 0.9398)
			(end -0.508 -0.9398)
			(stroke
				(width 0)
				(type default)
			)
			(fill no)
			(layer "B.CrtYd")
		)
		(fp_rect
			(start 0.508 0.9398)
			(end -0.508 -0.9398)
			(stroke
				(width 0)
				(type default)
			)
			(fill no)
			(layer "B.Fab")
		)
		(pad "1" smd custom
			(at 0 -0.4445)
			(size 0.1397 0.1397)
			(layers "B.Cu" "B.Mask" "B.Paste")
			(net "HOST3_RST_N_LS")
			(options
				(clearance outline)
				(anchor circle)
			)
			(primitives
				(gr_poly
					(pts
						(arc
							(start -0.1778 0.2794)
							(mid -0.249642 0.249642)
							(end -0.2794 0.1778)
						)
						(arc
							(start -0.2794 -0.1778)
							(mid -0.249642 -0.249642)
							(end -0.1778 -0.2794)
						)
						(arc
							(start 0.1778 -0.2794)
							(mid 0.249642 -0.249642)
							(end 0.2794 -0.1778)
						)
						(arc
							(start 0.2794 0.1778)
							(mid 0.249642 0.249642)
							(end 0.1778 0.2794)
						)
					)
					(width 0)
					(fill yes)
				)
			)
		)
		(pad "2" smd custom
			(at 0 0.4445)
			(size 0.1397 0.1397)
			(layers "B.Cu" "B.Mask" "B.Paste")
			(net "LBI_ADDR_2_R")
			(options
				(clearance outline)
				(anchor circle)
			)
			(primitives
				(gr_poly
					(pts
						(arc
							(start -0.1778 0.2794)
							(mid -0.249642 0.249642)
							(end -0.2794 0.1778)
						)
						(arc
							(start -0.2794 -0.1778)
							(mid -0.249642 -0.249642)
							(end -0.1778 -0.2794)
						)
						(arc
							(start 0.1778 -0.2794)
							(mid 0.249642 -0.249642)
							(end 0.2794 -0.1778)
						)
						(arc
							(start 0.2794 0.1778)
							(mid 0.249642 0.249642)
							(end 0.1778 0.2794)
						)
					)
					(width 0)
					(fill yes)
				)
			)
		)
	)
	(footprint ""
		(layer "B.Cu")
		(at 332.772512 -172.432218)
		(property "Reference" "R4163"
			(at 0 0 0)
			(layer "B.SilkS")
			(hide yes)
			(effects
				(font
					(size 1.27 1.27)
				)
				(justify mirror)
			)
		)
		(property "Value" "4K7R2F-GP"
			(at -0.064008 -3.993896 0)
			(unlocked yes)
			(layer "B.Fab")
			(hide yes)
			(effects
				(font
					(size 1.016 1.016)
					(thickness 0.1524)
				)
				(justify mirror)
			)
		)
		(property "Device Type" "R402H16"
			(at -0.064008 -5.517896 0)
			(unlocked yes)
			(layer "B.Fab")
			(hide yes)
			(effects
				(font
					(size 1.016 1.016)
					(thickness 0.1524)
				)
				(justify mirror)
			)
		)
		(duplicate_pad_numbers_are_jumpers no)
		(fp_line
			(start -0.508 -0.9398)
			(end 0.508 -0.9398)
			(stroke
				(width 0.1524)
				(type default)
			)
			(layer "B.SilkS")
		)
		(fp_line
			(start 0.508 -0.9398)
			(end 0.508 0.9398)
			(stroke
				(width 0.1524)
				(type default)
			)
			(layer "B.SilkS")
		)
		(fp_rect
			(start 0.508 0.9398)
			(end -0.508 -0.9398)
			(stroke
				(width 0)
				(type default)
			)
			(fill no)
			(layer "B.CrtYd")
		)
		(fp_rect
			(start 0.508 0.9398)
			(end -0.508 -0.9398)
			(stroke
				(width 0)
				(type default)
			)
			(fill no)
			(layer "B.Fab")
		)
		(pad "1" smd custom
			(at 0 -0.4445 180)
			(size 0.1397 0.1397)
			(layers "B.Cu" "B.Mask" "B.Paste")
			(net "SSD_PRSNT#4")
			(options
				(clearance outline)
				(anchor circle)
			)
			(primitives
				(gr_poly
					(pts
						(arc
							(start -0.1778 0.2794)
							(mid -0.249642 0.249642)
							(end -0.2794 0.1778)
						)
						(arc
							(start -0.2794 -0.1778)
							(mid -0.249642 -0.249642)
							(end -0.1778 -0.2794)
						)
						(arc
							(start 0.1778 -0.2794)
							(mid 0.249642 -0.249642)
							(end 0.2794 -0.1778)
						)
						(arc
							(start 0.2794 0.1778)
							(mid 0.249642 0.249642)
							(end 0.1778 0.2794)
						)
					)
					(width 0)
					(fill yes)
				)
			)
		)
		(pad "2" smd custom
			(at 0 0.4445 180)
			(size 0.1397 0.1397)
			(layers "B.Cu" "B.Mask" "B.Paste")
			(net "P3V3_STBY")
			(options
				(clearance outline)
				(anchor circle)
			)
			(primitives
				(gr_poly
					(pts
						(arc
							(start -0.1778 0.2794)
							(mid -0.249642 0.249642)
							(end -0.2794 0.1778)
						)
						(arc
							(start -0.2794 -0.1778)
							(mid -0.249642 -0.249642)
							(end -0.1778 -0.2794)
						)
						(arc
							(start 0.1778 -0.2794)
							(mid 0.249642 -0.249642)
							(end 0.2794 -0.1778)
						)
						(arc
							(start 0.2794 0.1778)
							(mid 0.249642 0.249642)
							(end 0.1778 0.2794)
						)
					)
					(width 0)
					(fill yes)
				)
			)
		)
	)
	(footprint ""
		(layer "B.Cu")
		(at 18.415 -126.619 -90)
		(property "Reference" "R236"
			(at 0 0 90)
			(layer "B.SilkS")
			(hide yes)
			(effects
				(font
					(size 1.27 1.27)
				)
				(justify mirror)
			)
		)
		(property "Value" "100KR2F-L1-GP"
			(at -0.064008 -3.993896 270)
			(unlocked yes)
			(layer "B.Fab")
			(hide yes)
			(effects
				(font
					(size 1.016 1.016)
					(thickness 0.1524)
				)
				(justify mirror)
			)
		)
		(property "Device Type" "R402H16"
			(at -0.064008 -5.517896 270)
			(unlocked yes)
			(layer "B.Fab")
			(hide yes)
			(effects
				(font
					(size 1.016 1.016)
					(thickness 0.1524)
				)
				(justify mirror)
			)
		)
		(duplicate_pad_numbers_are_jumpers no)
		(fp_line
			(start -0.508 -0.9398)
			(end 0.508 -0.9398)
			(stroke
				(width 0.1524)
				(type default)
			)
			(layer "B.SilkS")
		)
		(fp_line
			(start 0.508 -0.9398)
			(end 0.508 0.9398)
			(stroke
				(width 0.1524)
				(type default)
			)
			(layer "B.SilkS")
		)
		(fp_rect
			(start 0.508 0.9398)
			(end -0.508 -0.9398)
			(stroke
				(width 0)
				(type default)
			)
			(fill no)
			(layer "B.CrtYd")
		)
		(fp_rect
			(start 0.508 0.9398)
			(end -0.508 -0.9398)
			(stroke
				(width 0)
				(type default)
			)
			(fill no)
			(layer "B.Fab")
		)
		(pad "1" smd custom
			(at 0 -0.4445 90)
			(size 0.1397 0.1397)
			(layers "B.Cu" "B.Mask" "B.Paste")
			(net "GND")
			(options
				(clearance outline)
				(anchor circle)
			)
			(primitives
				(gr_poly
					(pts
						(arc
							(start -0.1778 0.2794)
							(mid -0.249642 0.249642)
							(end -0.2794 0.1778)
						)
						(arc
							(start -0.2794 -0.1778)
							(mid -0.249642 -0.249642)
							(end -0.1778 -0.2794)
						)
						(arc
							(start 0.1778 -0.2794)
							(mid 0.249642 -0.249642)
							(end 0.2794 -0.1778)
						)
						(arc
							(start 0.2794 0.1778)
							(mid 0.249642 0.249642)
							(end 0.1778 0.2794)
						)
					)
					(width 0)
					(fill yes)
				)
			)
		)
		(pad "2" smd custom
			(at 0 0.4445 90)
			(size 0.1397 0.1397)
			(layers "B.Cu" "B.Mask" "B.Paste")
			(net "TP_BMC0_LPC_LAD2")
			(options
				(clearance outline)
				(anchor circle)
			)
			(primitives
				(gr_poly
					(pts
						(arc
							(start -0.1778 0.2794)
							(mid -0.249642 0.249642)
							(end -0.2794 0.1778)
						)
						(arc
							(start -0.2794 -0.1778)
							(mid -0.249642 -0.249642)
							(end -0.1778 -0.2794)
						)
						(arc
							(start 0.1778 -0.2794)
							(mid 0.249642 -0.249642)
							(end 0.2794 -0.1778)
						)
						(arc
							(start 0.2794 0.1778)
							(mid 0.249642 0.249642)
							(end 0.1778 0.2794)
						)
					)
					(width 0)
					(fill yes)
				)
			)
		)
	)
	(footprint ""
		(layer "B.Cu")
		(at 273.2532 -0.889 90)
		(property "Reference" "R2913"
			(at 0 0 90)
			(layer "B.SilkS")
			(hide yes)
			(effects
				(font
					(size 1.27 1.27)
				)
				(justify mirror)
			)
		)
		(property "Value" "0R2J-2-GP"
			(at -0.064008 -3.993896 90)
			(unlocked yes)
			(layer "B.Fab")
			(hide yes)
			(effects
				(font
					(size 1.016 1.016)
					(thickness 0.1524)
				)
				(justify mirror)
			)
		)
		(property "Device Type" "R402H16"
			(at -0.064008 -5.517896 90)
			(unlocked yes)
			(layer "B.Fab")
			(hide yes)
			(effects
				(font
					(size 1.016 1.016)
					(thickness 0.1524)
				)
				(justify mirror)
			)
		)
		(duplicate_pad_numbers_are_jumpers no)
		(fp_line
			(start 0.508 -0.9398)
			(end 0.508 0.9398)
			(stroke
				(width 0.1524)
				(type default)
			)
			(layer "B.SilkS")
		)
		(fp_line
			(start -0.508 -0.9398)
			(end 0.508 -0.9398)
			(stroke
				(width 0.1524)
				(type default)
			)
			(layer "B.SilkS")
		)
		(fp_rect
			(start 0.508 0.9398)
			(end -0.508 -0.9398)
			(stroke
				(width 0)
				(type default)
			)
			(fill no)
			(layer "B.CrtYd")
		)
		(fp_rect
			(start 0.508 0.9398)
			(end -0.508 -0.9398)
			(stroke
				(width 0)
				(type default)
			)
			(fill no)
			(layer "B.Fab")
		)
		(pad "1" smd custom
			(at 0 -0.4445 270)
			(size 0.1397 0.1397)
			(layers "B.Cu" "B.Mask" "B.Paste")
			(net "CBL_PRSNT_N_8")
			(options
				(clearance outline)
				(anchor circle)
			)
			(primitives
				(gr_poly
					(pts
						(arc
							(start -0.1778 0.2794)
							(mid -0.249642 0.249642)
							(end -0.2794 0.1778)
						)
						(arc
							(start -0.2794 -0.1778)
							(mid -0.249642 -0.249642)
							(end -0.1778 -0.2794)
						)
						(arc
							(start 0.1778 -0.2794)
							(mid 0.249642 -0.249642)
							(end 0.2794 -0.1778)
						)
						(arc
							(start 0.2794 0.1778)
							(mid 0.249642 0.249642)
							(end 0.1778 0.2794)
						)
					)
					(width 0)
					(fill yes)
				)
			)
		)
		(pad "2" smd custom
			(at 0 0.4445 270)
			(size 0.1397 0.1397)
			(layers "B.Cu" "B.Mask" "B.Paste")
			(net "8644_SDA_R_8")
			(options
				(clearance outline)
				(anchor circle)
			)
			(primitives
				(gr_poly
					(pts
						(arc
							(start -0.1778 0.2794)
							(mid -0.249642 0.249642)
							(end -0.2794 0.1778)
						)
						(arc
							(start -0.2794 -0.1778)
							(mid -0.249642 -0.249642)
							(end -0.1778 -0.2794)
						)
						(arc
							(start 0.1778 -0.2794)
							(mid 0.249642 -0.249642)
							(end 0.2794 -0.1778)
						)
						(arc
							(start 0.2794 0.1778)
							(mid 0.249642 0.249642)
							(end 0.1778 0.2794)
						)
					)
					(width 0)
					(fill yes)
				)
			)
		)
	)
	(footprint ""
		(layer "B.Cu")
		(at 252.603 -58.005472 -90)
		(property "Reference" "C587"
			(at 0 0 90)
			(layer "B.SilkS")
			(hide yes)
			(effects
				(font
					(size 1.27 1.27)
				)
				(justify mirror)
			)
		)
		(property "Value" "SCD1U16V1KX-1-GP"
			(at 2.8321 -1.7399 270)
			(unlocked yes)
			(layer "B.Fab")
			(hide yes)
			(effects
				(font
					(size 1.016 1.016)
					(thickness 0.1524)
				)
				(justify mirror)
			)
		)
		(property "Device Type" "C0201H13"
			(at 2.8321 -3.2639 270)
			(unlocked yes)
			(layer "B.Fab")
			(hide yes)
			(effects
				(font
					(size 1.016 1.016)
					(thickness 0.1524)
				)
				(justify mirror)
			)
		)
		(duplicate_pad_numbers_are_jumpers no)
		(fp_rect
			(start 0.2794 0.6477)
			(end -0.2794 -0.6477)
			(stroke
				(width 0)
				(type default)
			)
			(fill no)
			(layer "B.CrtYd")
		)
		(fp_rect
			(start 0.2794 0.6477)
			(end -0.2794 -0.6477)
			(stroke
				(width 0)
				(type default)
			)
			(fill no)
			(layer "B.Fab")
		)
		(pad "1" smd custom
			(at 0 -0.2794 90)
			(size 0.0762 0.0762)
			(layers "B.Cu" "B.Mask" "B.Paste")
			(net "DUT_AVD_PCIE")
			(options
				(clearance outline)
				(anchor circle)
			)
			(primitives
				(gr_poly
					(pts
						(arc
							(start 0.1524 0.127)
							(mid 0.137521 0.162921)
							(end 0.1016 0.1778)
						)
						(arc
							(start -0.1016 0.1778)
							(mid -0.137521 0.162921)
							(end -0.1524 0.127)
						)
						(arc
							(start -0.1524 -0.127)
							(mid -0.137521 -0.162921)
							(end -0.1016 -0.1778)
						)
						(arc
							(start 0.1016 -0.1778)
							(mid 0.137521 -0.162921)
							(end 0.1524 -0.127)
						)
					)
					(width 0)
					(fill yes)
				)
			)
		)
		(pad "2" smd custom
			(at 0 0.2794 90)
			(size 0.0762 0.0762)
			(layers "B.Cu" "B.Mask" "B.Paste")
			(net "GND")
			(options
				(clearance outline)
				(anchor circle)
			)
			(primitives
				(gr_poly
					(pts
						(arc
							(start 0.1524 0.127)
							(mid 0.137521 0.162921)
							(end 0.1016 0.1778)
						)
						(arc
							(start -0.1016 0.1778)
							(mid -0.137521 0.162921)
							(end -0.1524 0.127)
						)
						(arc
							(start -0.1524 -0.127)
							(mid -0.137521 -0.162921)
							(end -0.1016 -0.1778)
						)
						(arc
							(start 0.1016 -0.1778)
							(mid 0.137521 -0.162921)
							(end 0.1524 -0.127)
						)
					)
					(width 0)
					(fill yes)
				)
			)
		)
	)
	(footprint ""
		(layer "B.Cu")
		(at 215.265 -194.0306)
		(property "Reference" "C3202"
			(at 0 0 0)
			(layer "B.SilkS")
			(hide yes)
			(effects
				(font
					(size 1.27 1.27)
				)
				(justify mirror)
			)
		)
		(property "Value" "SCD1U25V2KX-2-GP"
			(at -1.1811 -2.7051 0)
			(unlocked yes)
			(layer "B.Fab")
			(hide yes)
			(effects
				(font
					(size 1.016 1.016)
					(thickness 0.1524)
				)
				(justify mirror)
			)
		)
		(property "Device Type" "C402H22"
			(at -1.1811 -4.2291 0)
			(unlocked yes)
			(layer "B.Fab")
			(hide yes)
			(effects
				(font
					(size 1.016 1.016)
					(thickness 0.1524)
				)
				(justify mirror)
			)
		)
		(duplicate_pad_numbers_are_jumpers no)
		(fp_rect
			(start 0.4318 0.9525)
			(end -0.4318 -0.9525)
			(stroke
				(width 0)
				(type default)
			)
			(fill no)
			(layer "B.CrtYd")
		)
		(fp_rect
			(start 0.4318 0.9525)
			(end -0.4318 -0.9525)
			(stroke
				(width 0)
				(type default)
			)
			(fill no)
			(layer "B.Fab")
		)
		(pad "1" smd custom
			(at 0 -0.4445 180)
			(size 0.1524 0.1524)
			(layers "B.Cu" "B.Mask" "B.Paste")
			(net "P3V3_STBY")
			(options
				(clearance outline)
				(anchor circle)
			)
			(primitives
				(gr_poly
					(pts
						(arc
							(start 0.3048 0.2032)
							(mid 0.275042 0.275042)
							(end 0.2032 0.3048)
						)
						(arc
							(start -0.2032 0.3048)
							(mid -0.275042 0.275042)
							(end -0.3048 0.2032)
						)
						(arc
							(start -0.3048 -0.2032)
							(mid -0.275042 -0.275042)
							(end -0.2032 -0.3048)
						)
						(arc
							(start 0.2032 -0.3048)
							(mid 0.275042 -0.275042)
							(end 0.3048 -0.2032)
						)
					)
					(width 0)
					(fill yes)
				)
			)
		)
		(pad "2" smd custom
			(at 0 0.4445 180)
			(size 0.1524 0.1524)
			(layers "B.Cu" "B.Mask" "B.Paste")
			(net "GND")
			(options
				(clearance outline)
				(anchor circle)
			)
			(primitives
				(gr_poly
					(pts
						(arc
							(start 0.3048 0.2032)
							(mid 0.275042 0.275042)
							(end 0.2032 0.3048)
						)
						(arc
							(start -0.2032 0.3048)
							(mid -0.275042 0.275042)
							(end -0.3048 0.2032)
						)
						(arc
							(start -0.3048 -0.2032)
							(mid -0.275042 -0.275042)
							(end -0.2032 -0.3048)
						)
						(arc
							(start 0.2032 -0.3048)
							(mid 0.275042 -0.275042)
							(end 0.3048 -0.2032)
						)
					)
					(width 0)
					(fill yes)
				)
			)
		)
	)
	(footprint ""
		(layer "B.Cu")
		(at 53.756052 -110.19663 -90)
		(property "Reference" "U32"
			(at 0 0 90)
			(layer "B.SilkS")
			(hide yes)
			(effects
				(font
					(size 1.27 1.27)
				)
				(justify mirror)
			)
		)
		(property "Value" "2N7002DW-7F-GP"
			(at 2.3622 -8.2042 270)
			(unlocked yes)
			(layer "B.Fab")
			(hide yes)
			(effects
				(font
					(size 1.016 1.016)
					(thickness 0.1524)
				)
				(justify mirror)
			)
		)
		(property "Device Type" "SOT-363H44"
			(at 2.3622 -10.1092 270)
			(unlocked yes)
			(layer "B.Fab")
			(hide yes)
			(effects
				(font
					(size 1.016 1.016)
					(thickness 0.1524)
				)
				(justify mirror)
			)
		)
		(duplicate_pad_numbers_are_jumpers no)
		(fp_line
			(start -1.4478 1.7018)
			(end -1.4478 -1.7018)
			(stroke
				(width 0.1524)
				(type default)
			)
			(layer "B.SilkS")
		)
		(fp_line
			(start 1.4478 1.7018)
			(end -1.4478 1.7018)
			(stroke
				(width 0.1524)
				(type default)
			)
			(layer "B.SilkS")
		)
		(fp_line
			(start 1.27 1.524)
			(end 1.27 0.6604)
			(stroke
				(width 0.4826)
				(type default)
			)
			(layer "B.SilkS")
		)
		(fp_line
			(start -1.4478 -1.7018)
			(end 1.4478 -1.7018)
			(stroke
				(width 0.1524)
				(type default)
			)
			(layer "B.SilkS")
		)
		(fp_line
			(start 1.4478 -1.7018)
			(end 1.4478 1.7018)
			(stroke
				(width 0.1524)
				(type default)
			)
			(layer "B.SilkS")
		)
		(fp_poly
			(pts
				(xy 1.524 -1.778) (xy -1.524 -1.778) (xy -1.524 1.778) (xy 1.524 1.778)
			)
			(stroke
				(width 0)
				(type default)
			)
			(fill no)
			(layer "B.CrtYd")
		)
		(fp_poly
			(pts
				(xy 1.524 -1.778) (xy -1.524 -1.778) (xy -1.524 1.778) (xy 1.524 1.778)
			)
			(stroke
				(width 0)
				(type default)
			)
			(fill no)
			(layer "B.Fab")
		)
		(pad "1" smd rect
			(at 0.65024 0.9398 90)
			(size 0.4064 1.016)
			(layers "B.Cu" "B.Mask" "B.Paste")
			(net "BMC_I2C12_MINI6_SCL_S")
		)
		(pad "2" smd rect
			(at 0 0.9398 90)
			(size 0.4064 1.016)
			(layers "B.Cu" "B.Mask" "B.Paste")
			(net "I2C6_LS_G2")
		)
		(pad "3" smd rect
			(at -0.65024 0.9398 90)
			(size 0.4064 1.016)
			(layers "B.Cu" "B.Mask" "B.Paste")
			(net "BMC_I2C12_MINI6_SDA")
		)
		(pad "4" smd rect
			(at -0.65024 -0.9398 90)
			(size 0.4064 1.016)
			(layers "B.Cu" "B.Mask" "B.Paste")
			(net "BMC_I2C12_MINI6_SDA_S")
		)
		(pad "5" smd rect
			(at 0 -0.9398 90)
			(size 0.4064 1.016)
			(layers "B.Cu" "B.Mask" "B.Paste")
			(net "I2C6_LS_G1")
		)
		(pad "6" smd rect
			(at 0.65024 -0.9398 90)
			(size 0.4064 1.016)
			(layers "B.Cu" "B.Mask" "B.Paste")
			(net "BMC_I2C12_MINI6_SCL")
		)
	)
)
